FILE_TYPE = CONNECTIVITY;
{Allegro Design Entry HDL 16.6-p007 (v16-6-112F) 10/10/2012}
"PAGE_NUMBER" = 135;
0"NC";
1"P3V3_STBY\g";
2"P3V3_STBY\g";
3"GND\g";
4"P3V3_STBY\g";
5"P3V3_STBY\g";
6"P3V3_STBY\g";
7"GND\g";
8"GND\g";
9"P3V3_STBY\g";
10"GND\g";
11"PU_KEY_CONN_PIN2_R";
12"FM_QAT_EN_N";
13"FM_PCH_SATA_RAID_KEY";
14"TP_JUMPER_BLOCK_1_8";
15"TP_JUMPER_BLOCK_1_2";
16"FM_DIS_ADR_DLY";
17"FM_IE_DISABLE_N";
18"TP_JUMPER_BLOCK_1_1";
19"RST_BMC_SRST_N";
20"TP_JUMPER_BLOCK_ 1_7";
21"FM_CPLD_UART_CH_LOCK_N";
22"FM_PCH_SATA_RAID_KEY_R";
%"P3V3_STBY"
"1","(200,2525)","0","mstr_symbols","I106";
;
VOLTAGE"3.3V"
SIZE"1B"
CDS_LIB"mstr_symbols"
BODY_TYPE"PLUMBING"
HDL_POWER"P3V3_STBY";
"G\NAC"1;
%"RES"
"2","(200,2225)","0","mstr_discrete","I107";
;
CDS_SEC"1"
CDS_LOCATION"R2P19"
PART_NUMBER"G21796-016"
PACK_TYPE"0402"
TOLERANCE"1%"
MATERIAL"CHIP"
WATTAGE"1/16W"
VALUE"10.0K"
LOCATION"R2P19"
ROOM"CPLD"
SEC_TYPE"0402"
BOM_COST"CPLD"
SEC"1"
CDS_LIB"mstr_discrete";
"A"
$PN"1"1;
"B"
$PN"2"16;
%"P3V3_STBY"
"1","(-2150,5025)","0","mstr_symbols","I111";
;
VOLTAGE"3.3V"
CDS_LIB"mstr_symbols"
SIZE"1B"
BODY_TYPE"PLUMBING"
HDL_POWER"P3V3_STBY";
"G\NAC"2;
%"RES"
"2","(-2150,4775)","0","mstr_discrete","I112";
;
LOCATION"R2N23"
PART_NUMBER"G21796-016"
VALUE"10.0K"
TOLERANCE"1%"
PACK_TYPE"0402"
MATERIAL"CHIP"
WATTAGE"1/16W"
ROOM"SB"
CDS_SEC"1"
$SEC"1"
CDS_LOCATION"R2N23"
CDS_LIB"mstr_discrete";
"A"
$PN"1"2;
"B"
$PN"2"12;
%"RES"
"2","(-2150,4325)","0","mstr_discrete","I113";
;
CDS_SEC"1"
PART_NUMBER"G21796-026"
MATERIAL"EMPTY"
LOCATION"R2N24"
TOLERANCE"1%"
PACK_TYPE"0402"
WATTAGE"1/16W"
VALUE"1.00K"
ROOM"SB"
SEC_TYPE"0402"
SEC"1"
CDS_LOCATION"R2N24"
CDS_LIB"mstr_discrete";
"A"
$PN"1"12;
"B"
$PN"2"3;
%"GND"
"1","(-2150,4125)","0","mstr_symbols","I114";
;
VOLTAGE"0.0V"
CDS_LIB"mstr_symbols"
SIZE"1B"
BODY_TYPE"PLUMBING"
HDL_POWER"GND";
"A\NAC"3;
%"P3V3_STBY"
"1","(-3875,5150)","0","mstr_symbols","I116";
;
VOLTAGE"3.3V"
SIZE"1B"
CDS_LIB"mstr_symbols"
BODY_TYPE"PLUMBING"
HDL_POWER"P3V3_STBY";
"G\NAC"4;
%"RES"
"1","(-3875,4900)","1","mstr_discrete","I117";
;
MATERIAL"CHIP"
WATTAGE"1/16W"
LOCATION"R9A12"
VALUE"2.21K"
TOLERANCE"1%"
PACK_TYPE"0402"
PART_NUMBER"G21796-112"
ROOM"SB"
CDS_LOCATION"R9A12"
$SEC"1"
CDS_SEC"1"
BOM_COST"SB"
CDS_LIB"mstr_discrete";
"B"
$PN"2"4;
"A"
$PN"1"22;
%"RES"
"1","(-3650,4500)","0","mstr_discrete","I118";
;
VALUE"33.2"
WATTAGE"1/16W"
PART_NUMBER"G21796-074"
TOLERANCE"1%"
PACK_TYPE"0402"
MATERIAL"CHIP"
LOCATION"R9A13"
ROOM"SB"
$SEC"1"
CDS_SEC"1"
BOM_COST"SB"
CDS_LOCATION"R9A13"
CDS_LIB"mstr_discrete";
"B"
$PN"2"13;
"A"
$PN"1"22;
%"P3V3_STBY"
"1","(-225,2525)","0","mstr_symbols","I119";
;
VOLTAGE"3.3V"
CDS_LIB"mstr_symbols"
SIZE"1B"
BODY_TYPE"PLUMBING"
HDL_POWER"P3V3_STBY";
"G\NAC"5;
%"RES"
"2","(-225,2250)","0","mstr_discrete","I120";
;
CDS_SEC"1"
WATTAGE"1/16W"
PACK_TYPE"0402"
PART_NUMBER"G21796-026"
VALUE"1.00K"
TOLERANCE"1%"
MATERIAL"CHIP"
LOCATION"R8D21"
ROOM"SB"
BOM_COST"SB"
SEC"1"
SEC_TYPE"0402"
CDS_LOCATION"R8D21"
CDS_LIB"mstr_discrete";
"A"
$PN"1"5;
"B"
$PN"2"17;
%"RES"
"2","(-1525,2250)","0","mstr_discrete","I121";
;
CDS_SEC"1"
PACK_TYPE"0402"
VALUE"4.75K"
LOCATION"R7D30"
PART_NUMBER"G21796-072"
TOLERANCE"1%"
MATERIAL"CHIP"
WATTAGE"1/16W"
ROOM"UART_MUX"
SEC_TYPE"0402"
BOM_COST"DEBUG"
SEC"1"
CDS_LOCATION"R7D30"
CDS_LIB"mstr_discrete";
"A"
$PN"1"6;
"B"
$PN"2"21;
%"P3V3_STBY"
"1","(-1525,2500)","0","mstr_symbols","I122";
;
VOLTAGE"3.3V"
SIZE"1B"
CDS_LIB"mstr_symbols"
BODY_TYPE"PLUMBING"
HDL_POWER"P3V3_STBY";
"G\NAC"6;
%"GND"
"1","(-300,1600)","0","mstr_symbols","I123";
;
VOLTAGE"0.0V"
SIZE"1B"
CDS_LIB"mstr_symbols"
BODY_TYPE"PLUMBING"
HDL_POWER"GND";
"A\NAC"7;
%"CONN12_C73564003"
"1","(-775,1900)","0","mstr_conn","I124";
;
CDS_SEC"1"
CDS_LOCATION"J8G2"
PART_NUMBER"C73564-003"
MATERIAL"CONN"
LOCATION"J8G2"
PACK_TYPE"PIP"
ROOM"SB"
SEC_TYPE"PIP"
SEC"1"
CDS_LIB"mstr_conn"
BOM_COST"SB";
"IO9"
$PN"9"21;
"IO11"
$PN"11"8;
"IO7"
$PN"7"20;
"IO3"
$PN"3"19;
"IO1"
$PN"1"18;
"IO5"
$PN"5"8;
"IO8"
$PN"8"14;
"IO10"
$PN"10"16;
"IO12"
$PN"12"7;
"IO6"
$PN"6"7;
"IO4"
$PN"4"17;
"IO2"
$PN"2"15;
%"GND"
"1","(-1250,1575)","0","mstr_symbols","I125";
;
VOLTAGE"0.0V"
CDS_LIB"mstr_symbols"
SIZE"1B"
BODY_TYPE"PLUMBING"
HDL_POWER"GND";
"A\NAC"8;
%"P3V3_STBY"
"1","(-4275,5150)","0","mstr_symbols","I128";
;
VOLTAGE"3.3V"
SIZE"1B"
CDS_LIB"mstr_symbols"
BODY_TYPE"PLUMBING"
HDL_POWER"P3V3_STBY";
"G\NAC"9;
%"RES"
"1","(-4275,4900)","1","mstr_discrete","I129";
;
VALUE"2.21K"
LOCATION"R9A16"
TOLERANCE"1%"
PACK_TYPE"0402"
MATERIAL"CHIP"
PART_NUMBER"G21796-112"
WATTAGE"1/16W"
ROOM"SB"
CDS_SEC"1"
$SEC"1"
CDS_LOCATION"R9A16"
BOM_COST"SB"
CDS_LIB"mstr_discrete";
"B"
$PN"2"9;
"A"
$PN"1"11;
%"GND"
"1","(-4850,4425)","0","mstr_symbols","I130";
;
BOM_COST"SB"
SIZE"1B"
CDS_LIB"mstr_symbols"
ROOM"WBG_HEADERS_BIOS"
VOLTAGE"0"
BODY_TYPE"PLUMBING"
HDL_POWER"GND";
"A\NAC"10;
%"CONN4_D42317002"
"1","(-5075,4600)","2","mstr_conn","I131";
;
POP"NOPOP"
LOCATION"J9A1"
PART_NUMBER"D42317-002"
MATERIAL"CONN"
PACK_TYPE"PIP"
ROOM"SB"
CDS_LOCATION"J9A1"
$SEC"1"
CDS_SEC"1"
BOM_COST"SB"
CDS_LIB"mstr_conn";
"IO4"
$PN"4"22;
"IO3"
$PN"3"10;
"IO2"
$PN"2"11;
"IO1"
$PN"1"10;
END.
